# BASEBOARD_FAB2 (Tioga Pass) — schematic netlist excerpt (pin names and nets, part order shuffled) for the footprints in the layout excerpt that follows; sources: Cadence DE-HDL packaged netlist, KiCad conversion of Wiwynn_Tioga_Pass_MB.brd

R6L5  RES  1.0M 1% EMPTY  pkg 0402  page 230 : A = P3V3 ; B = FM_PVTT_KLM_EN_R
C25W53  CAP  1.0UF 16V 10% X6S  pkg 0402  page 149 : A = P1V2_AUX_BMC ; B = GND
C25W27  CAP  1.0UF 16V 10% X6S  pkg 0402  page 149 : A = P1V15_AUX_BMC ; B = GND

(kicad_pcb
	(version 20260206)
	(generator "pcbnew")
	(generator_version "10.0")
	(general
		(thickness 1.6)
		(legacy_teardrops no)
	)
	(paper "A4")
	(title_block
		(title "Wiwynn_Tioga_Pass_MB.brd")
		(comment 1 "Tioga Pass / footprints 4393-4395 of 4770")
	)
	(layers
		(0 "F.Cu" signal "TOP")
		(4 "In1.Cu" signal "L2GND")
		(6 "In2.Cu" signal "L3")
		(8 "In3.Cu" signal "L4GND")
		(10 "In4.Cu" signal "L5")
		(12 "In5.Cu" signal "L6GND")
		(14 "In6.Cu" signal "L7VCC")
		(16 "In7.Cu" signal "L8VCC")
		(18 "In8.Cu" signal "L9GND")
		(20 "In9.Cu" signal "L10")
		(22 "In10.Cu" signal "L11GND")
		(24 "In11.Cu" signal "L12")
		(26 "In12.Cu" signal "L13GND")
		(2 "B.Cu" signal "BOTTOM")
		(9 "F.Adhes" user "F.Adhesive")
		(11 "B.Adhes" user "B.Adhesive")
		(13 "F.Paste" user "Package Geometry/Pastemask Top")
		(15 "B.Paste" user "Package Geometry/Pastemask Bottom")
		(5 "F.SilkS" user "Ref Des/Silkscreen Top")
		(7 "B.SilkS" user "Ref Des/Silkscreen Bottom")
		(1 "F.Mask" user "Board Geometry/Soldermask Top")
		(3 "B.Mask" user "Board Geometry/Soldermask Bottom")
		(17 "Dwgs.User" user "User.Drawings")
		(19 "Cmts.User" user "User.Comments")
		(21 "Eco1.User" user "User.Eco1")
		(23 "Eco2.User" user "User.Eco2")
		(25 "Edge.Cuts" user "Board Geometry/Outline")
		(27 "Margin" user)
		(31 "F.CrtYd" user "Package Geometry/Place Bound Top")
		(29 "B.CrtYd" user "Package Geometry/Place Bound Bottom")
		(35 "F.Fab" user "Ref Des/Assembly Top")
		(33 "B.Fab" user "Ref Des/Assembly Bottom")
	)
	(footprint ""
		(layer "B.Cu")
		(at 416.883596 -32.327342 180)
		(property "Reference" "C25W27"
			(at 0.8382 -0.67818 180)
			(unlocked yes)
			(layer "B.SilkS")
			(effects
				(font
					(size 0.4064 0.254)
					(thickness 0.1524)
				)
				(justify left mirror)
			)
		)
		(property "Value" ""
			(at 0 0 0)
			(layer "B.Fab")
			(effects
				(font
					(size 1.27 1.27)
				)
				(justify mirror)
			)
		)
		(duplicate_pad_numbers_are_jumpers no)
		(fp_poly
			(pts
				(xy -0.3048 -0.1016) (xy -0.3048 0.9906) (xy 0.3048 0.9906) (xy 0.3048 -0.1016)
			)
			(stroke
				(width 0)
				(type default)
			)
			(fill no)
			(layer "B.CrtYd")
		)
		(fp_line
			(start 0.3048 0.9906)
			(end -0.3048 0.9906)
			(stroke
				(width 0.1)
				(type default)
			)
			(layer "B.Fab")
		)
		(fp_line
			(start 0.3048 -0.1016)
			(end 0.3048 0.9906)
			(stroke
				(width 0.1)
				(type default)
			)
			(layer "B.Fab")
		)
		(fp_line
			(start -0.3048 0.9906)
			(end -0.3048 -0.1016)
			(stroke
				(width 0.1)
				(type default)
			)
			(layer "B.Fab")
		)
		(fp_line
			(start -0.3048 -0.1016)
			(end 0.3048 -0.1016)
			(stroke
				(width 0.1)
				(type default)
			)
			(layer "B.Fab")
		)
		(pad "1" smd rect
			(at 0 0)
			(size 0.508 0.508)
			(layers "B.Cu" "B.Mask" "B.Paste")
			(net "P1V15_AUX_BMC")
		)
		(pad "2" smd rect
			(at 0 0.889)
			(size 0.508 0.508)
			(layers "B.Cu" "B.Mask" "B.Paste")
			(net "GND")
		)
		(zone
			(layer "B.Cu")
			(hatch none 0.5)
			(connect_pads
				(clearance 0)
			)
			(min_thickness 0.25)
			(keepout
				(tracks not_allowed)
				(vias allowed)
				(pads allowed)
				(copperpour not_allowed)
				(footprints allowed)
			)
			(placement
				(enabled no)
				(sheetname "")
			)
			(fill
				(thermal_gap 0.5)
				(thermal_bridge_width 0.5)
				(island_removal_mode 0)
			)
			(polygon
				(pts
					(xy 416.629596 -32.962342) (xy 417.137596 -32.962342) (xy 417.137596 -32.581342) (xy 416.629596 -32.581342)
				)
			)
		)
		(zone
			(layer "B.Cu")
			(hatch none 0.5)
			(connect_pads
				(clearance 0)
			)
			(min_thickness 0.25)
			(keepout
				(tracks allowed)
				(vias not_allowed)
				(pads allowed)
				(copperpour not_allowed)
				(footprints allowed)
			)
			(placement
				(enabled no)
				(sheetname "")
			)
			(fill
				(thermal_gap 0.5)
				(thermal_bridge_width 0.5)
				(island_removal_mode 0)
			)
			(polygon
				(pts
					(xy 416.629596 -32.581342) (xy 417.137596 -32.581342) (xy 417.137596 -32.962342) (xy 416.629596 -32.962342)
				)
			)
		)
	)
	(footprint ""
		(layer "B.Cu")
		(at 168.61028 -148.7424 -90)
		(property "Reference" "R6L5"
			(at 0 0 90)
			(layer "B.SilkS")
			(hide yes)
			(effects
				(font
					(size 1.27 1.27)
				)
				(justify mirror)
			)
		)
		(property "Value" ""
			(at 0 0 90)
			(layer "B.Fab")
			(effects
				(font
					(size 1.27 1.27)
				)
				(justify mirror)
			)
		)
		(duplicate_pad_numbers_are_jumpers no)
		(fp_rect
			(start -0.2794 -0.1016)
			(end 0.2794 0.9906)
			(stroke
				(width 0)
				(type default)
			)
			(fill no)
			(layer "B.CrtYd")
		)
		(fp_line
			(start -0.2794 0.9906)
			(end -0.2794 -0.1016)
			(stroke
				(width 0.1)
				(type default)
			)
			(layer "B.Fab")
		)
		(fp_line
			(start 0.2794 0.9906)
			(end -0.2794 0.9906)
			(stroke
				(width 0.1)
				(type default)
			)
			(layer "B.Fab")
		)
		(fp_line
			(start -0.2794 -0.1016)
			(end 0.2794 -0.1016)
			(stroke
				(width 0.1)
				(type default)
			)
			(layer "B.Fab")
		)
		(fp_line
			(start 0.2794 -0.1016)
			(end 0.2794 0.9906)
			(stroke
				(width 0.1)
				(type default)
			)
			(layer "B.Fab")
		)
		(pad "1" smd rect
			(at 0 0 90)
			(size 0.508 0.508)
			(layers "B.Cu" "B.Mask" "B.Paste")
			(net "P3V3")
		)
		(pad "2" smd rect
			(at 0 0.889 90)
			(size 0.508 0.508)
			(layers "B.Cu" "B.Mask" "B.Paste")
			(net "FM_PVTT_KLM_EN_R")
		)
		(zone
			(layer "B.Cu")
			(hatch none 0.5)
			(connect_pads
				(clearance 0)
			)
			(min_thickness 0.25)
			(keepout
				(tracks not_allowed)
				(vias allowed)
				(pads allowed)
				(copperpour not_allowed)
				(footprints allowed)
			)
			(placement
				(enabled no)
				(sheetname "")
			)
			(fill
				(thermal_gap 0.5)
				(thermal_bridge_width 0.5)
				(island_removal_mode 0)
			)
			(polygon
				(pts
					(xy 168.35628 -148.9964) (xy 167.97528 -148.9964) (xy 167.97528 -148.4884) (xy 168.35628 -148.4884)
				)
			)
		)
		(zone
			(layer "B.Cu")
			(hatch none 0.5)
			(connect_pads
				(clearance 0)
			)
			(min_thickness 0.25)
			(keepout
				(tracks allowed)
				(vias not_allowed)
				(pads allowed)
				(copperpour not_allowed)
				(footprints allowed)
			)
			(placement
				(enabled no)
				(sheetname "")
			)
			(fill
				(thermal_gap 0.5)
				(thermal_bridge_width 0.5)
				(island_removal_mode 0)
			)
			(polygon
				(pts
					(xy 168.35628 -148.9964) (xy 167.97528 -148.9964) (xy 167.97528 -148.4884) (xy 168.35628 -148.4884)
				)
			)
		)
	)
	(footprint ""
		(layer "B.Cu")
		(at 418.719 -35.1155 180)
		(property "Reference" "C25W53"
			(at 0.8382 -0.67818 180)
			(unlocked yes)
			(layer "B.SilkS")
			(effects
				(font
					(size 0.4064 0.254)
					(thickness 0.1524)
				)
				(justify left mirror)
			)
		)
		(property "Value" ""
			(at 0 0 0)
			(layer "B.Fab")
			(effects
				(font
					(size 1.27 1.27)
				)
				(justify mirror)
			)
		)
		(duplicate_pad_numbers_are_jumpers no)
		(fp_poly
			(pts
				(xy -0.3048 -0.1016) (xy -0.3048 0.9906) (xy 0.3048 0.9906) (xy 0.3048 -0.1016)
			)
			(stroke
				(width 0)
				(type default)
			)
			(fill no)
			(layer "B.CrtYd")
		)
		(fp_line
			(start 0.3048 0.9906)
			(end -0.3048 0.9906)
			(stroke
				(width 0.1)
				(type default)
			)
			(layer "B.Fab")
		)
		(fp_line
			(start 0.3048 -0.1016)
			(end 0.3048 0.9906)
			(stroke
				(width 0.1)
				(type default)
			)
			(layer "B.Fab")
		)
		(fp_line
			(start -0.3048 0.9906)
			(end -0.3048 -0.1016)
			(stroke
				(width 0.1)
				(type default)
			)
			(layer "B.Fab")
		)
		(fp_line
			(start -0.3048 -0.1016)
			(end 0.3048 -0.1016)
			(stroke
				(width 0.1)
				(type default)
			)
			(layer "B.Fab")
		)
		(pad "1" smd rect
			(at 0 0)
			(size 0.508 0.508)
			(layers "B.Cu" "B.Mask" "B.Paste")
			(net "P1V2_AUX_BMC")
		)
		(pad "2" smd rect
			(at 0 0.889)
			(size 0.508 0.508)
			(layers "B.Cu" "B.Mask" "B.Paste")
			(net "GND")
		)
		(zone
			(layer "B.Cu")
			(hatch none 0.5)
			(connect_pads
				(clearance 0)
			)
			(min_thickness 0.25)
			(keepout
				(tracks not_allowed)
				(vias allowed)
				(pads allowed)
				(copperpour not_allowed)
				(footprints allowed)
			)
			(placement
				(enabled no)
				(sheetname "")
			)
			(fill
				(thermal_gap 0.5)
				(thermal_bridge_width 0.5)
				(island_removal_mode 0)
			)
			(polygon
				(pts
					(xy 418.465 -35.7505) (xy 418.973 -35.7505) (xy 418.973 -35.3695) (xy 418.465 -35.3695)
				)
			)
		)
		(zone
			(layer "B.Cu")
			(hatch none 0.5)
			(connect_pads
				(clearance 0)
			)
			(min_thickness 0.25)
			(keepout
				(tracks allowed)
				(vias not_allowed)
				(pads allowed)
				(copperpour not_allowed)
				(footprints allowed)
			)
			(placement
				(enabled no)
				(sheetname "")
			)
			(fill
				(thermal_gap 0.5)
				(thermal_bridge_width 0.5)
				(island_removal_mode 0)
			)
			(polygon
				(pts
					(xy 418.465 -35.3695) (xy 418.973 -35.3695) (xy 418.973 -35.7505) (xy 418.465 -35.7505)
				)
			)
		)
	)
)
